# S9S_MB_2U (Grand Teton) — schematic netlist excerpt (pin names and nets, part order shuffled) for the footprints in the layout excerpt that follows; sources: Cadence DE-HDL packaged netlist, KiCad conversion of 03242023_DA0F0TMBIJ0_F0T_Motherboard_J_brd_V01_OCP.brd

C1013  Q_CAP  22UF 4V 20% X6S  pkg C0402  page 74 : A = PVCCIN_CPU0 ; B = GND
R1641  Q_RES  100K 1% CHIP  pkg 0402LF  page 260 : A = VR_P5V_EN ; B = GND

(kicad_pcb
	(version 20260206)
	(generator "pcbnew")
	(generator_version "10.0")
	(general
		(thickness 1.6)
		(legacy_teardrops no)
	)
	(paper "A4")
	(title_block
		(title "03242023_DA0F0TMBIJ0_F0T_Motherboard_J_brd_V01_OCP.brd")
		(comment 1 "Grand Teton / footprints 3084-3085 of 6105")
	)
	(layers
		(0 "F.Cu" signal "TOP")
		(4 "In1.Cu" signal "GND")
		(6 "In2.Cu" signal "IN1")
		(8 "In3.Cu" signal "GND1")
		(10 "In4.Cu" signal "IN2")
		(12 "In5.Cu" signal "GND2")
		(14 "In6.Cu" signal "IN3")
		(16 "In7.Cu" signal "GND3")
		(18 "In8.Cu" signal "VCC")
		(20 "In9.Cu" signal "VCC1")
		(22 "In10.Cu" signal "GND4")
		(24 "In11.Cu" signal "IN4")
		(26 "In12.Cu" signal "GND5")
		(28 "In13.Cu" signal "IN5")
		(30 "In14.Cu" signal "GND6")
		(32 "In15.Cu" signal "IN6")
		(34 "In16.Cu" signal "GND7")
		(2 "B.Cu" signal "BOTTOM")
		(9 "F.Adhes" user "F.Adhesive")
		(11 "B.Adhes" user "B.Adhesive")
		(13 "F.Paste" user "Package Geometry/Pastemask Top")
		(15 "B.Paste" user "Package Geometry/Pastemask Bottom")
		(5 "F.SilkS" user "Ref Des/Silkscreen Top")
		(7 "B.SilkS" user "Ref Des/Silkscreen Bottom")
		(1 "F.Mask" user "Board Geometry/Soldermask Top")
		(3 "B.Mask" user "Board Geometry/Soldermask Bottom")
		(17 "Dwgs.User" user "User.Drawings")
		(19 "Cmts.User" user "User.Comments")
		(21 "Eco1.User" user "User.Eco1")
		(23 "Eco2.User" user "User.Eco2")
		(25 "Edge.Cuts" user "Board Geometry/Outline")
		(27 "Margin" user)
		(31 "F.CrtYd" user "Package Geometry/Place Bound Top")
		(29 "B.CrtYd" user "Package Geometry/Place Bound Bottom")
		(35 "F.Fab" user "Ref Des/Assembly Top")
		(33 "B.Fab" user "Ref Des/Assembly Bottom")
	)
	(footprint ""
		(layer "F.Cu")
		(at 365.46663 -244.03177 90)
		(property "Reference" "C1013"
			(at 0 0 90)
			(layer "F.SilkS")
			(hide yes)
			(effects
				(font
					(size 1.27 1.27)
				)
			)
		)
		(property "Value" ""
			(at 0 0 90)
			(layer "F.Fab")
			(effects
				(font
					(size 1.27 1.27)
				)
			)
		)
		(duplicate_pad_numbers_are_jumpers no)
		(fp_line
			(start 0.7874 -0.4064)
			(end 0.7874 0.4064)
			(stroke
				(width 0.1524)
				(type default)
			)
			(layer "F.SilkS")
		)
		(fp_line
			(start -0.7874 -0.4064)
			(end 0.7874 -0.4064)
			(stroke
				(width 0.1524)
				(type default)
			)
			(layer "F.SilkS")
		)
		(fp_line
			(start 0.7874 0.4064)
			(end -0.7874 0.4064)
			(stroke
				(width 0.1524)
				(type default)
			)
			(layer "F.SilkS")
		)
		(fp_line
			(start -0.7874 0.4064)
			(end -0.7874 -0.4064)
			(stroke
				(width 0.1524)
				(type default)
			)
			(layer "F.SilkS")
		)
		(fp_line
			(start -0.12065 -0.305054)
			(end -0.12065 -0.2794)
			(stroke
				(width 0.1)
				(type default)
			)
			(layer "F.Fab")
		)
		(fp_line
			(start -0.67945 -0.305054)
			(end -0.12065 -0.305054)
			(stroke
				(width 0.1)
				(type default)
			)
			(layer "F.Fab")
		)
		(fp_line
			(start 0.67945 -0.3048)
			(end 0.67945 0.3048)
			(stroke
				(width 0.1)
				(type default)
			)
			(layer "F.Fab")
		)
		(fp_line
			(start 0.12065 -0.3048)
			(end 0.67945 -0.3048)
			(stroke
				(width 0.1)
				(type default)
			)
			(layer "F.Fab")
		)
		(fp_line
			(start 0.12065 -0.2794)
			(end 0.12065 -0.3048)
			(stroke
				(width 0.1)
				(type default)
			)
			(layer "F.Fab")
		)
		(fp_line
			(start -0.12065 -0.2794)
			(end 0.12065 -0.2794)
			(stroke
				(width 0.1)
				(type default)
			)
			(layer "F.Fab")
		)
		(fp_line
			(start 0.120396 0.2794)
			(end -0.12065 0.2794)
			(stroke
				(width 0.1)
				(type default)
			)
			(layer "F.Fab")
		)
		(fp_line
			(start -0.12065 0.2794)
			(end -0.12065 0.3048)
			(stroke
				(width 0.1)
				(type default)
			)
			(layer "F.Fab")
		)
		(fp_line
			(start 0.67945 0.3048)
			(end 0.120396 0.3048)
			(stroke
				(width 0.1)
				(type default)
			)
			(layer "F.Fab")
		)
		(fp_line
			(start 0.120396 0.3048)
			(end 0.120396 0.2794)
			(stroke
				(width 0.1)
				(type default)
			)
			(layer "F.Fab")
		)
		(fp_line
			(start -0.12065 0.3048)
			(end -0.67945 0.3048)
			(stroke
				(width 0.1)
				(type default)
			)
			(layer "F.Fab")
		)
		(fp_line
			(start -0.67945 0.3048)
			(end -0.67945 -0.305054)
			(stroke
				(width 0.1)
				(type default)
			)
			(layer "F.Fab")
		)
		(pad "1" smd circle
			(at -0.40005 0 90)
			(size 0 0)
			(layers "F.Cu" "F.Mask" "F.Paste")
			(net "PVCCIN_CPU0")
		)
		(pad "2" smd circle
			(at 0.40005 0 90)
			(size 0 0)
			(layers "F.Cu" "F.Mask" "F.Paste")
			(net "GND")
		)
	)
	(footprint ""
		(layer "F.Cu")
		(at 167.395906 -131.976114 90)
		(property "Reference" "R1641"
			(at 0 0 90)
			(layer "F.SilkS")
			(hide yes)
			(effects
				(font
					(size 1.27 1.27)
				)
			)
		)
		(property "Value" ""
			(at 0 0 90)
			(layer "F.Fab")
			(effects
				(font
					(size 1.27 1.27)
				)
			)
		)
		(duplicate_pad_numbers_are_jumpers no)
		(fp_line
			(start 0.7874 -0.4064)
			(end 0.7874 0.4064)
			(stroke
				(width 0.1524)
				(type default)
			)
			(layer "F.SilkS")
		)
		(fp_line
			(start -0.7874 -0.4064)
			(end 0.7874 -0.4064)
			(stroke
				(width 0.1524)
				(type default)
			)
			(layer "F.SilkS")
		)
		(fp_line
			(start 0.7874 0.4064)
			(end -0.7874 0.4064)
			(stroke
				(width 0.1524)
				(type default)
			)
			(layer "F.SilkS")
		)
		(fp_line
			(start -0.7874 0.4064)
			(end -0.7874 -0.4064)
			(stroke
				(width 0.1524)
				(type default)
			)
			(layer "F.SilkS")
		)
		(fp_line
			(start -0.12065 -0.305054)
			(end -0.12065 -0.2794)
			(stroke
				(width 0.1)
				(type default)
			)
			(layer "F.Fab")
		)
		(fp_line
			(start -0.67945 -0.305054)
			(end -0.12065 -0.305054)
			(stroke
				(width 0.1)
				(type default)
			)
			(layer "F.Fab")
		)
		(fp_line
			(start 0.67945 -0.3048)
			(end 0.67945 0.3048)
			(stroke
				(width 0.1)
				(type default)
			)
			(layer "F.Fab")
		)
		(fp_line
			(start 0.12065 -0.3048)
			(end 0.67945 -0.3048)
			(stroke
				(width 0.1)
				(type default)
			)
			(layer "F.Fab")
		)
		(fp_line
			(start 0.12065 -0.2794)
			(end 0.12065 -0.3048)
			(stroke
				(width 0.1)
				(type default)
			)
			(layer "F.Fab")
		)
		(fp_line
			(start -0.12065 -0.2794)
			(end 0.12065 -0.2794)
			(stroke
				(width 0.1)
				(type default)
			)
			(layer "F.Fab")
		)
		(fp_line
			(start 0.120396 0.2794)
			(end -0.12065 0.2794)
			(stroke
				(width 0.1)
				(type default)
			)
			(layer "F.Fab")
		)
		(fp_line
			(start -0.12065 0.2794)
			(end -0.12065 0.3048)
			(stroke
				(width 0.1)
				(type default)
			)
			(layer "F.Fab")
		)
		(fp_line
			(start 0.67945 0.3048)
			(end 0.120396 0.3048)
			(stroke
				(width 0.1)
				(type default)
			)
			(layer "F.Fab")
		)
		(fp_line
			(start 0.120396 0.3048)
			(end 0.120396 0.2794)
			(stroke
				(width 0.1)
				(type default)
			)
			(layer "F.Fab")
		)
		(fp_line
			(start -0.12065 0.3048)
			(end -0.67945 0.3048)
			(stroke
				(width 0.1)
				(type default)
			)
			(layer "F.Fab")
		)
		(fp_line
			(start -0.67945 0.3048)
			(end -0.67945 -0.305054)
			(stroke
				(width 0.1)
				(type default)
			)
			(layer "F.Fab")
		)
		(pad "1" smd circle
			(at -0.40005 0 90)
			(size 0 0)
			(layers "F.Cu" "F.Mask" "F.Paste")
			(net "VR_P5V_EN")
		)
		(pad "2" smd circle
			(at 0.40005 0 90)
			(size 0 0)
			(layers "F.Cu" "F.Mask" "F.Paste")
			(net "GND")
		)
	)
)
